(kicad_pcb
	(version 20260206)
	(generator "pcbnew")
	(generator_version "10.0")
	(general
		(thickness 1.6)
		(legacy_teardrops no)
	)
	(paper "A4")
	(title_block
		(title "timecard-production-celestica-r4006 — R4006-B0001-02_R01.brd")
		(comment 1 "Time Appliance Project (Time Card) / footprints 867-871 of 1113")
	)
	(layers
		(0 "F.Cu" signal "TOP")
		(4 "In1.Cu" signal "L02_GND1")
		(6 "In2.Cu" signal "L03_SIG1")
		(8 "In3.Cu" signal "L04_GND2")
		(10 "In4.Cu" signal "L05_VCC1")
		(12 "In5.Cu" signal "L06_VCC2")
		(14 "In6.Cu" signal "L07_GND3")
		(16 "In7.Cu" signal "L08_SIG2")
		(18 "In8.Cu" signal "L09_GND4")
		(2 "B.Cu" signal "BOTTOM")
		(9 "F.Adhes" user "F.Adhesive")
		(11 "B.Adhes" user "B.Adhesive")
		(13 "F.Paste" user "Package Geometry/Pastemask Top")
		(15 "B.Paste" user "Package Geometry/Pastemask Bottom")
		(5 "F.SilkS" user "Ref Des/Silkscreen Top")
		(7 "B.SilkS" user "Ref Des/Silkscreen Bottom")
		(1 "F.Mask" user "Board Geometry/Soldermask Top")
		(3 "B.Mask" user "Board Geometry/Soldermask Bottom")
		(17 "Dwgs.User" user "User.Drawings")
		(19 "Cmts.User" user "User.Comments")
		(21 "Eco1.User" user "User.Eco1")
		(23 "Eco2.User" user "User.Eco2")
		(25 "Edge.Cuts" user "Board Geometry/Outline")
		(27 "Margin" user)
		(31 "F.CrtYd" user "Package Geometry/Place Bound Top")
		(29 "B.CrtYd" user "Package Geometry/Place Bound Bottom")
		(35 "F.Fab" user "Ref Des/Assembly Top")
		(33 "B.Fab" user "Ref Des/Assembly Bottom")
	)
	(footprint ""
		(layer "B.Cu")
		(at 101.347016 -48.823118)
		(property "Reference" "C167"
			(at -1.144016 1.052068 0)
			(unlocked yes)
			(layer "B.SilkS")
			(effects
				(font
					(size 0.635 0.4064)
					(thickness 0.1524)
				)
				(justify mirror)
			)
		)
		(property "Value" "VAL*"
			(at 0 3.718306 0)
			(unlocked yes)
			(layer "B.Fab")
			(hide yes)
			(effects
				(font
					(size 0.7874 0.5842)
					(thickness 0.127)
				)
				(justify mirror)
			)
		)
		(property "Device Type" "CAPACITOR-G105-0F475-BM,4.7UF,A"
			(at 0 1.432306 0)
			(unlocked yes)
			(layer "B.Fab")
			(hide yes)
			(effects
				(font
					(size 0.7874 0.5842)
					(thickness 0.127)
				)
				(justify mirror)
			)
		)
		(property "User Part Number" "PARTNUM*"
			(at 0 2.575306 0)
			(unlocked yes)
			(layer "Cmts.User")
			(hide yes)
			(effects
				(font
					(size 0.7874 0.5842)
					(thickness 0.127)
				)
				(justify mirror)
			)
		)
		(property "Tolerance" "TOL*"
			(at 0 4.861306 0)
			(unlocked yes)
			(layer "Cmts.User")
			(hide yes)
			(effects
				(font
					(size 0.7874 0.5842)
					(thickness 0.127)
				)
				(justify mirror)
			)
		)
		(duplicate_pad_numbers_are_jumpers no)
		(fp_line
			(start -0.970026 -0.4699)
			(end -0.970026 0.4699)
			(stroke
				(width 0.1)
				(type default)
			)
			(layer "B.SilkS")
		)
		(fp_line
			(start -0.970026 0.4699)
			(end 0.970026 0.4699)
			(stroke
				(width 0.1)
				(type default)
			)
			(layer "B.SilkS")
		)
		(fp_line
			(start 0.970026 -0.4699)
			(end -0.970026 -0.4699)
			(stroke
				(width 0.1)
				(type default)
			)
			(layer "B.SilkS")
		)
		(fp_line
			(start 0.970026 0.4699)
			(end 0.970026 -0.4699)
			(stroke
				(width 0.1)
				(type default)
			)
			(layer "B.SilkS")
		)
		(fp_poly
			(pts
				(xy 0.970026 0.4699) (xy -0.970026 0.4699) (xy -0.970026 -0.4699) (xy 0.970026 -0.4699)
			)
			(stroke
				(width 0)
				(type default)
			)
			(fill no)
			(layer "B.CrtYd")
		)
		(fp_line
			(start -0.508 -0.3048)
			(end -0.508 0.3048)
			(stroke
				(width 0.1)
				(type default)
			)
			(layer "B.Fab")
		)
		(fp_line
			(start -0.508 0.3048)
			(end 0.508 0.3048)
			(stroke
				(width 0.1)
				(type default)
			)
			(layer "B.Fab")
		)
		(fp_line
			(start 0.508 -0.3048)
			(end -0.508 -0.3048)
			(stroke
				(width 0.1)
				(type default)
			)
			(layer "B.Fab")
		)
		(fp_line
			(start 0.508 0.3048)
			(end 0.508 -0.3048)
			(stroke
				(width 0.1)
				(type default)
			)
			(layer "B.Fab")
		)
		(pad "1" smd circle
			(at 0.500126 0 180)
			(size 0.635 0.635)
			(layers "B.Cu" "B.Mask" "B.Paste")
			(net "XP3R3V_FPGA")
		)
		(pad "2" smd circle
			(at -0.500126 0 180)
			(size 0.635 0.635)
			(layers "B.Cu" "B.Mask" "B.Paste")
			(net "SG")
		)
	)
	(footprint ""
		(layer "B.Cu")
		(at 5.588 -73.025)
		(property "Reference" "R336"
			(at -2.921 -0.59563 0)
			(unlocked yes)
			(layer "B.SilkS")
			(effects
				(font
					(size 0.7874 0.5842)
					(thickness 0.1524)
				)
				(justify mirror)
			)
		)
		(property "Value" "VAL*"
			(at -0.02032 2.13233 0)
			(unlocked yes)
			(layer "B.Fab")
			(hide yes)
			(effects
				(font
					(size 0.7874 0.5842)
					(thickness 0.1524)
				)
				(justify mirror)
			)
		)
		(property "Tolerance" "TOL*"
			(at -0.044704 3.05435 0)
			(unlocked yes)
			(layer "Cmts.User")
			(hide yes)
			(effects
				(font
					(size 0.7874 0.5842)
					(thickness 0.1524)
				)
				(justify mirror)
			)
		)
		(property "User Part Number" "PARTNUM*"
			(at -0.02032 4.024884 0)
			(unlocked yes)
			(layer "Cmts.User")
			(hide yes)
			(effects
				(font
					(size 0.7874 0.5842)
					(thickness 0.1524)
				)
				(justify mirror)
			)
		)
		(property "Device Type" "RESISTOR-G155-11001-01,1KOHM,1%"
			(at -0.008382 1.210564 0)
			(unlocked yes)
			(layer "B.Fab")
			(hide yes)
			(effects
				(font
					(size 0.7874 0.5842)
					(thickness 0.1524)
				)
				(justify mirror)
			)
		)
		(duplicate_pad_numbers_are_jumpers no)
		(fp_line
			(start -1.143 -0.5588)
			(end 1.143 -0.5588)
			(stroke
				(width 0.1)
				(type default)
			)
			(layer "B.SilkS")
		)
		(fp_line
			(start -1.143 0.5588)
			(end -1.143 -0.5588)
			(stroke
				(width 0.1)
				(type default)
			)
			(layer "B.SilkS")
		)
		(fp_line
			(start 1.143 -0.5588)
			(end 1.143 0.5588)
			(stroke
				(width 0.1)
				(type default)
			)
			(layer "B.SilkS")
		)
		(fp_line
			(start 1.143 0.5588)
			(end -1.143 0.5588)
			(stroke
				(width 0.1)
				(type default)
			)
			(layer "B.SilkS")
		)
		(fp_rect
			(start 1.143 0.5588)
			(end -1.143 -0.5588)
			(stroke
				(width 0)
				(type default)
			)
			(fill no)
			(layer "B.CrtYd")
		)
		(fp_line
			(start -0.508 -0.3048)
			(end 0.508 -0.3048)
			(stroke
				(width 0.1)
				(type default)
			)
			(layer "B.Fab")
		)
		(fp_line
			(start -0.508 0.3048)
			(end -0.508 -0.3048)
			(stroke
				(width 0.1)
				(type default)
			)
			(layer "B.Fab")
		)
		(fp_line
			(start 0.508 -0.3048)
			(end 0.508 0.3048)
			(stroke
				(width 0.1)
				(type default)
			)
			(layer "B.Fab")
		)
		(fp_line
			(start 0.508 0.3048)
			(end -0.508 0.3048)
			(stroke
				(width 0.1)
				(type default)
			)
			(layer "B.Fab")
		)
		(pad "1" smd rect
			(at 0.5334 0 180)
			(size 0.7112 0.6096)
			(layers "B.Cu" "B.Mask" "B.Paste")
			(net "UNNAMED_6_LM75BDPTSSOP8_I34_A1")
		)
		(pad "2" smd rect
			(at -0.5334 0 180)
			(size 0.7112 0.6096)
			(layers "B.Cu" "B.Mask" "B.Paste")
			(net "SG")
		)
		(zone
			(layer "B.Cu")
			(hatch none 0.5)
			(connect_pads
				(clearance 0)
			)
			(min_thickness 0.25)
			(keepout
				(tracks allowed)
				(vias not_allowed)
				(pads allowed)
				(copperpour not_allowed)
				(footprints allowed)
			)
			(placement
				(enabled no)
				(sheetname "")
			)
			(fill
				(thermal_gap 0.5)
				(thermal_bridge_width 0.5)
				(island_removal_mode 0)
			)
			(polygon
				(pts
					(xy 5.6642 -72.7202) (xy 5.6642 -73.3298) (xy 5.5118 -73.3298) (xy 5.5118 -72.7202)
				)
			)
		)
	)
	(footprint ""
		(layer "B.Cu")
		(at 116.34724 -47.82312 180)
		(property "Reference" "R270"
			(at 42.94124 -2.71907 0)
			(unlocked yes)
			(layer "B.SilkS")
			(effects
				(font
					(size 0.635 0.4064)
					(thickness 0.1524)
				)
				(justify mirror)
			)
		)
		(property "Value" "VAL*"
			(at 0 3.718306 180)
			(unlocked yes)
			(layer "B.Fab")
			(hide yes)
			(effects
				(font
					(size 0.7874 0.5842)
					(thickness 0.127)
				)
				(justify mirror)
			)
		)
		(property "Tolerance" "TOL*"
			(at 0 4.861306 180)
			(unlocked yes)
			(layer "Cmts.User")
			(hide yes)
			(effects
				(font
					(size 0.7874 0.5842)
					(thickness 0.127)
				)
				(justify mirror)
			)
		)
		(property "User Part Number" "PARTNUM*"
			(at 0 2.575306 180)
			(unlocked yes)
			(layer "Cmts.User")
			(hide yes)
			(effects
				(font
					(size 0.7874 0.5842)
					(thickness 0.127)
				)
				(justify mirror)
			)
		)
		(property "Device Type" "RESISTOR-G155-14701-01,4.7KOHMA"
			(at 0 1.432306 180)
			(unlocked yes)
			(layer "B.Fab")
			(hide yes)
			(effects
				(font
					(size 0.7874 0.5842)
					(thickness 0.127)
				)
				(justify mirror)
			)
		)
		(duplicate_pad_numbers_are_jumpers no)
		(fp_line
			(start 0.970026 0.4699)
			(end 0.970026 -0.4699)
			(stroke
				(width 0.1)
				(type default)
			)
			(layer "B.SilkS")
		)
		(fp_line
			(start 0.970026 -0.4699)
			(end -0.970026 -0.4699)
			(stroke
				(width 0.1)
				(type default)
			)
			(layer "B.SilkS")
		)
		(fp_line
			(start -0.970026 0.4699)
			(end 0.970026 0.4699)
			(stroke
				(width 0.1)
				(type default)
			)
			(layer "B.SilkS")
		)
		(fp_line
			(start -0.970026 -0.4699)
			(end -0.970026 0.4699)
			(stroke
				(width 0.1)
				(type default)
			)
			(layer "B.SilkS")
		)
		(fp_poly
			(pts
				(xy 0.970026 0.4699) (xy -0.970026 0.4699) (xy -0.970026 -0.4699) (xy 0.970026 -0.4699)
			)
			(stroke
				(width 0)
				(type default)
			)
			(fill no)
			(layer "B.CrtYd")
		)
		(fp_line
			(start 0.508 0.3048)
			(end 0.508 -0.3048)
			(stroke
				(width 0.1)
				(type default)
			)
			(layer "B.Fab")
		)
		(fp_line
			(start 0.508 -0.3048)
			(end -0.508 -0.3048)
			(stroke
				(width 0.1)
				(type default)
			)
			(layer "B.Fab")
		)
		(fp_line
			(start -0.508 0.3048)
			(end 0.508 0.3048)
			(stroke
				(width 0.1)
				(type default)
			)
			(layer "B.Fab")
		)
		(fp_line
			(start -0.508 -0.3048)
			(end -0.508 0.3048)
			(stroke
				(width 0.1)
				(type default)
			)
			(layer "B.Fab")
		)
		(pad "1" smd circle
			(at 0.500126 0)
			(size 0.635 0.635)
			(layers "B.Cu" "B.Mask" "B.Paste")
			(net "SG")
		)
		(pad "2" smd circle
			(at -0.500126 0)
			(size 0.635 0.635)
			(layers "B.Cu" "B.Mask" "B.Paste")
			(net "FPGA_IN_GPSTP1_OUT")
		)
	)
	(footprint ""
		(layer "B.Cu")
		(at 113.919 -61.976 -90)
		(property "Reference" "R216"
			(at -3.429 -0.08763 270)
			(unlocked yes)
			(layer "B.SilkS")
			(effects
				(font
					(size 0.7874 0.5842)
					(thickness 0.1524)
				)
				(justify mirror)
			)
		)
		(property "Value" "VAL*"
			(at -0.02032 2.13233 270)
			(unlocked yes)
			(layer "B.Fab")
			(hide yes)
			(effects
				(font
					(size 0.7874 0.5842)
					(thickness 0.1524)
				)
				(justify mirror)
			)
		)
		(property "Device Type" "RESISTOR-G155-11001-01,1KOHM,1%"
			(at -0.008382 1.210564 270)
			(unlocked yes)
			(layer "B.Fab")
			(hide yes)
			(effects
				(font
					(size 0.7874 0.5842)
					(thickness 0.1524)
				)
				(justify mirror)
			)
		)
		(property "User Part Number" "PARTNUM*"
			(at -0.02032 4.024884 270)
			(unlocked yes)
			(layer "Cmts.User")
			(hide yes)
			(effects
				(font
					(size 0.7874 0.5842)
					(thickness 0.1524)
				)
				(justify mirror)
			)
		)
		(property "Tolerance" "TOL*"
			(at -0.044704 3.05435 270)
			(unlocked yes)
			(layer "Cmts.User")
			(hide yes)
			(effects
				(font
					(size 0.7874 0.5842)
					(thickness 0.1524)
				)
				(justify mirror)
			)
		)
		(duplicate_pad_numbers_are_jumpers no)
		(fp_line
			(start -1.143 0.5588)
			(end -1.143 -0.5588)
			(stroke
				(width 0.1)
				(type default)
			)
			(layer "B.SilkS")
		)
		(fp_line
			(start 1.143 0.5588)
			(end -1.143 0.5588)
			(stroke
				(width 0.1)
				(type default)
			)
			(layer "B.SilkS")
		)
		(fp_line
			(start -1.143 -0.5588)
			(end 1.143 -0.5588)
			(stroke
				(width 0.1)
				(type default)
			)
			(layer "B.SilkS")
		)
		(fp_line
			(start 1.143 -0.5588)
			(end 1.143 0.5588)
			(stroke
				(width 0.1)
				(type default)
			)
			(layer "B.SilkS")
		)
		(fp_rect
			(start 1.143 0.5588)
			(end -1.143 -0.5588)
			(stroke
				(width 0)
				(type default)
			)
			(fill no)
			(layer "B.CrtYd")
		)
		(fp_line
			(start -0.508 0.3048)
			(end -0.508 -0.3048)
			(stroke
				(width 0.1)
				(type default)
			)
			(layer "B.Fab")
		)
		(fp_line
			(start 0.508 0.3048)
			(end -0.508 0.3048)
			(stroke
				(width 0.1)
				(type default)
			)
			(layer "B.Fab")
		)
		(fp_line
			(start -0.508 -0.3048)
			(end 0.508 -0.3048)
			(stroke
				(width 0.1)
				(type default)
			)
			(layer "B.Fab")
		)
		(fp_line
			(start 0.508 -0.3048)
			(end 0.508 0.3048)
			(stroke
				(width 0.1)
				(type default)
			)
			(layer "B.Fab")
		)
		(pad "1" smd rect
			(at 0.5334 0 90)
			(size 0.7112 0.6096)
			(layers "B.Cu" "B.Mask" "B.Paste")
			(net "FPGA_BRD_REV1")
		)
		(pad "2" smd rect
			(at -0.5334 0 90)
			(size 0.7112 0.6096)
			(layers "B.Cu" "B.Mask" "B.Paste")
			(net "SG")
		)
		(zone
			(layer "B.Cu")
			(hatch none 0.5)
			(connect_pads
				(clearance 0)
			)
			(min_thickness 0.25)
			(keepout
				(tracks allowed)
				(vias not_allowed)
				(pads allowed)
				(copperpour not_allowed)
				(footprints allowed)
			)
			(placement
				(enabled no)
				(sheetname "")
			)
			(fill
				(thermal_gap 0.5)
				(thermal_bridge_width 0.5)
				(island_removal_mode 0)
			)
			(polygon
				(pts
					(xy 113.6142 -61.8998) (xy 114.2238 -61.8998) (xy 114.2238 -62.0522) (xy 113.6142 -62.0522)
				)
			)
		)
	)
	(footprint ""
		(layer "B.Cu")
		(at 124.587 -51.435 180)
		(property "Reference" "R264"
			(at -3.302 -0.16637 0)
			(unlocked yes)
			(layer "B.SilkS")
			(effects
				(font
					(size 0.7874 0.5842)
					(thickness 0.1524)
				)
				(justify mirror)
			)
		)
		(property "Value" "VAL*"
			(at -0.02032 2.13233 180)
			(unlocked yes)
			(layer "B.Fab")
			(hide yes)
			(effects
				(font
					(size 0.7874 0.5842)
					(thickness 0.1524)
				)
				(justify mirror)
			)
		)
		(property "Tolerance" "TOL*"
			(at -0.044704 3.05435 180)
			(unlocked yes)
			(layer "Cmts.User")
			(hide yes)
			(effects
				(font
					(size 0.7874 0.5842)
					(thickness 0.1524)
				)
				(justify mirror)
			)
		)
		(property "User Part Number" "PARTNUM*"
			(at -0.02032 4.024884 180)
			(unlocked yes)
			(layer "Cmts.User")
			(hide yes)
			(effects
				(font
					(size 0.7874 0.5842)
					(thickness 0.1524)
				)
				(justify mirror)
			)
		)
		(property "Device Type" "RESISTOR-G155-11003-01,100KOHMA"
			(at -0.008382 1.210564 180)
			(unlocked yes)
			(layer "B.Fab")
			(hide yes)
			(effects
				(font
					(size 0.7874 0.5842)
					(thickness 0.1524)
				)
				(justify mirror)
			)
		)
		(duplicate_pad_numbers_are_jumpers no)
		(fp_line
			(start 1.143 0.5588)
			(end -1.143 0.5588)
			(stroke
				(width 0.1)
				(type default)
			)
			(layer "B.SilkS")
		)
		(fp_line
			(start 1.143 -0.5588)
			(end 1.143 0.5588)
			(stroke
				(width 0.1)
				(type default)
			)
			(layer "B.SilkS")
		)
		(fp_line
			(start -1.143 0.5588)
			(end -1.143 -0.5588)
			(stroke
				(width 0.1)
				(type default)
			)
			(layer "B.SilkS")
		)
		(fp_line
			(start -1.143 -0.5588)
			(end 1.143 -0.5588)
			(stroke
				(width 0.1)
				(type default)
			)
			(layer "B.SilkS")
		)
		(fp_rect
			(start 1.143 0.5588)
			(end -1.143 -0.5588)
			(stroke
				(width 0)
				(type default)
			)
			(fill no)
			(layer "B.CrtYd")
		)
		(fp_line
			(start 0.508 0.3048)
			(end -0.508 0.3048)
			(stroke
				(width 0.1)
				(type default)
			)
			(layer "B.Fab")
		)
		(fp_line
			(start 0.508 -0.3048)
			(end 0.508 0.3048)
			(stroke
				(width 0.1)
				(type default)
			)
			(layer "B.Fab")
		)
		(fp_line
			(start -0.508 0.3048)
			(end -0.508 -0.3048)
			(stroke
				(width 0.1)
				(type default)
			)
			(layer "B.Fab")
		)
		(fp_line
			(start -0.508 -0.3048)
			(end 0.508 -0.3048)
			(stroke
				(width 0.1)
				(type default)
			)
			(layer "B.Fab")
		)
		(pad "1" smd rect
			(at 0.5334 0)
			(size 0.7112 0.6096)
			(layers "B.Cu" "B.Mask" "B.Paste")
			(net "XP3R3V_FPGA")
		)
		(pad "2" smd rect
			(at -0.5334 0)
			(size 0.7112 0.6096)
			(layers "B.Cu" "B.Mask" "B.Paste")
			(net "R_MAC_UART_RX_FPGA_TX")
		)
		(zone
			(layer "B.Cu")
			(hatch none 0.5)
			(connect_pads
				(clearance 0)
			)
			(min_thickness 0.25)
			(keepout
				(tracks not_allowed)
				(vias allowed)
				(pads allowed)
				(copperpour not_allowed)
				(footprints allowed)
			)
			(placement
				(enabled no)
				(sheetname "")
			)
			(fill
				(thermal_gap 0.5)
				(thermal_bridge_width 0.5)
				(island_removal_mode 0)
			)
			(polygon
				(pts
					(xy 124.5108 -51.7398) (xy 124.5108 -51.1302) (xy 124.6632 -51.1302) (xy 124.6632 -51.7398)
				)
			)
		)
		(zone
			(layer "B.Cu")
			(hatch none 0.5)
			(connect_pads
				(clearance 0)
			)
			(min_thickness 0.25)
			(keepout
				(tracks allowed)
				(vias not_allowed)
				(pads allowed)
				(copperpour not_allowed)
				(footprints allowed)
			)
			(placement
				(enabled no)
				(sheetname "")
			)
			(fill
				(thermal_gap 0.5)
				(thermal_bridge_width 0.5)
				(island_removal_mode 0)
			)
			(polygon
				(pts
					(xy 124.5108 -51.7398) (xy 124.5108 -51.1302) (xy 124.6632 -51.1302) (xy 124.6632 -51.7398)
				)
			)
		)
	)
)
